(kicad_pcb
	(version 20260206)
	(generator "pcbnew")
	(generator_version "10.0")
	(general
		(thickness 1.6)
		(legacy_teardrops no)
	)
	(paper "A4")
	(title_block
		(title "Bryce Canyon_F.DPB_16315-1-OCP.brd")
		(comment 1 "Bryce Canyon / footprints 1981-1988 of 2223")
	)
	(layers
		(0 "F.Cu" signal "TOP")
		(4 "In1.Cu" signal "L2GND")
		(6 "In2.Cu" signal "L3")
		(8 "In3.Cu" signal "L4GND")
		(10 "In4.Cu" signal "L5")
		(12 "In5.Cu" signal "L6VCC")
		(14 "In6.Cu" signal "L7VCC")
		(16 "In7.Cu" signal "L8")
		(18 "In8.Cu" signal "L9GND")
		(20 "In9.Cu" signal "L10")
		(22 "In10.Cu" signal "L11GND")
		(2 "B.Cu" signal "BOTTOM")
		(9 "F.Adhes" user "F.Adhesive")
		(11 "B.Adhes" user "B.Adhesive")
		(13 "F.Paste" user "Package Geometry/Pastemask Top")
		(15 "B.Paste" user "Package Geometry/Pastemask Bottom")
		(5 "F.SilkS" user "Ref Des/Silkscreen Top")
		(7 "B.SilkS" user "Ref Des/Silkscreen Bottom")
		(1 "F.Mask" user "Board Geometry/Soldermask Top")
		(3 "B.Mask" user "Board Geometry/Soldermask Bottom")
		(17 "Dwgs.User" user "User.Drawings")
		(19 "Cmts.User" user "User.Comments")
		(21 "Eco1.User" user "User.Eco1")
		(23 "Eco2.User" user "User.Eco2")
		(25 "Edge.Cuts" user "Board Geometry/Outline")
		(27 "Margin" user)
		(31 "F.CrtYd" user "Package Geometry/Place Bound Top")
		(29 "B.CrtYd" user "Package Geometry/Place Bound Bottom")
		(35 "F.Fab" user "Ref Des/Assembly Top")
		(33 "B.Fab" user "Ref Des/Assembly Bottom")
	)
	(footprint ""
		(layer "F.Cu")
		(at 370.259102 -171.809918 -90)
		(property "Reference" "R582"
			(at 0 0 270)
			(layer "F.SilkS")
			(hide yes)
			(effects
				(font
					(size 1.27 1.27)
				)
			)
		)
		(property "Value" "300KR2F-GP"
			(at 0.064008 -3.993896 270)
			(unlocked yes)
			(layer "F.Fab")
			(hide yes)
			(effects
				(font
					(size 1.016 1.016)
					(thickness 0.1524)
				)
			)
		)
		(property "Device Type" "R402H16"
			(at 0.064008 -5.517896 270)
			(unlocked yes)
			(layer "F.Fab")
			(hide yes)
			(effects
				(font
					(size 1.016 1.016)
					(thickness 0.1524)
				)
			)
		)
		(duplicate_pad_numbers_are_jumpers no)
		(fp_line
			(start -0.508 -0.9398)
			(end -0.508 0.9398)
			(stroke
				(width 0.1524)
				(type default)
			)
			(layer "F.SilkS")
		)
		(fp_line
			(start 0.508 -0.9398)
			(end -0.508 -0.9398)
			(stroke
				(width 0.1524)
				(type default)
			)
			(layer "F.SilkS")
		)
		(fp_rect
			(start -0.508 0.9398)
			(end 0.508 -0.9398)
			(stroke
				(width 0)
				(type default)
			)
			(fill no)
			(layer "F.CrtYd")
		)
		(fp_rect
			(start -0.508 0.9398)
			(end 0.508 -0.9398)
			(stroke
				(width 0)
				(type default)
			)
			(fill no)
			(layer "F.Fab")
		)
		(pad "1" smd custom
			(at 0 -0.4445 270)
			(size 0.1397 0.1397)
			(layers "F.Cu" "F.Mask" "F.Paste")
			(net "SW_HDD_N19")
			(options
				(clearance outline)
				(anchor circle)
			)
			(primitives
				(gr_poly
					(pts
						(arc
							(start -0.1778 -0.2794)
							(mid -0.249642 -0.249642)
							(end -0.2794 -0.1778)
						)
						(arc
							(start -0.2794 0.1778)
							(mid -0.249642 0.249642)
							(end -0.1778 0.2794)
						)
						(arc
							(start 0.1778 0.2794)
							(mid 0.249642 0.249642)
							(end 0.2794 0.1778)
						)
						(arc
							(start 0.2794 -0.1778)
							(mid 0.249642 -0.249642)
							(end 0.1778 -0.2794)
						)
					)
					(width 0)
					(fill yes)
				)
			)
		)
		(pad "2" smd custom
			(at 0 0.4445 270)
			(size 0.1397 0.1397)
			(layers "F.Cu" "F.Mask" "F.Paste")
			(net "P12V_A")
			(options
				(clearance outline)
				(anchor circle)
			)
			(primitives
				(gr_poly
					(pts
						(arc
							(start -0.1778 -0.2794)
							(mid -0.249642 -0.249642)
							(end -0.2794 -0.1778)
						)
						(arc
							(start -0.2794 0.1778)
							(mid -0.249642 0.249642)
							(end -0.1778 0.2794)
						)
						(arc
							(start 0.1778 0.2794)
							(mid 0.249642 0.249642)
							(end 0.2794 0.1778)
						)
						(arc
							(start 0.2794 -0.1778)
							(mid 0.249642 -0.249642)
							(end 0.1778 -0.2794)
						)
					)
					(width 0)
					(fill yes)
				)
			)
		)
	)
	(footprint ""
		(layer "F.Cu")
		(at 255.364234 -11.186922 90)
		(property "Reference" "TP217"
			(at 0 0 90)
			(layer "F.SilkS")
			(hide yes)
			(effects
				(font
					(size 1.27 1.27)
				)
			)
		)
		(property "Value" "TPAD32-GP"
			(at -0.0508 -1.6764 90)
			(unlocked yes)
			(layer "F.Fab")
			(hide yes)
			(effects
				(font
					(size 1.016 1.016)
					(thickness 0.1524)
				)
			)
		)
		(property "Device Type" "TPAD32"
			(at -0.0508 -3.2004 90)
			(unlocked yes)
			(layer "F.Fab")
			(hide yes)
			(effects
				(font
					(size 1.016 1.016)
					(thickness 0.1524)
				)
			)
		)
		(duplicate_pad_numbers_are_jumpers no)
		(fp_poly
			(pts
				(arc
					(start 0 0.4064)
					(mid 0 -0.4064)
					(end 0 0.4064)
				)
			)
			(stroke
				(width 0)
				(type default)
			)
			(fill no)
			(layer "F.CrtYd")
		)
		(fp_poly
			(pts
				(arc
					(start 0 0.7112)
					(mid 0 -0.7112)
					(end 0 0.7112)
				)
			)
			(stroke
				(width 0)
				(type default)
			)
			(fill no)
			(layer "F.Fab")
		)
		(pad "1" smd circle
			(at 0 0 90)
			(size 0.8128 0.8128)
			(layers "F.Cu" "F.Mask" "F.Paste")
			(net "TP_COMP_A_NCSI_RXD1")
		)
	)
	(footprint ""
		(layer "F.Cu")
		(at 77.815948 -294.683942 -90)
		(property "Reference" "C71"
			(at 0 0 270)
			(layer "F.SilkS")
			(hide yes)
			(effects
				(font
					(size 1.27 1.27)
				)
			)
		)
		(property "Value" "SC4D7U25V5KX-1-GP"
			(at -0.0762 -6.1214 270)
			(unlocked yes)
			(layer "F.Fab")
			(hide yes)
			(effects
				(font
					(size 1.016 1.016)
					(thickness 0.1524)
				)
			)
		)
		(property "Device Type" "C805H58"
			(at -0.0762 -8.1534 270)
			(unlocked yes)
			(layer "F.Fab")
			(hide yes)
			(effects
				(font
					(size 1.016 1.016)
					(thickness 0.1524)
				)
			)
		)
		(duplicate_pad_numbers_are_jumpers no)
		(fp_line
			(start 0.635 0)
			(end -0.635 0)
			(stroke
				(width 0.508)
				(type default)
			)
			(layer "F.SilkS")
		)
		(fp_rect
			(start -0.9652 1.778)
			(end 0.9652 -1.778)
			(stroke
				(width 0)
				(type default)
			)
			(fill no)
			(layer "F.CrtYd")
		)
		(fp_poly
			(pts
				(xy -0.9652 -1.778) (xy 0.9652 -1.778) (xy 0.9652 1.778) (xy -0.9652 1.778)
			)
			(stroke
				(width 0)
				(type default)
			)
			(fill no)
			(layer "F.Fab")
		)
		(pad "1" smd rect
			(at 0 -0.9652 270)
			(size 1.397 1.143)
			(layers "F.Cu" "F.Mask" "F.Paste")
			(net "P12V_HDD2")
		)
		(pad "2" smd rect
			(at 0 0.9652 270)
			(size 1.397 1.143)
			(layers "F.Cu" "F.Mask" "F.Paste")
			(net "GND")
		)
	)
	(footprint ""
		(layer "F.Cu")
		(at 381.00635 -65.039494 -90)
		(property "Reference" "R870"
			(at 0 0 270)
			(layer "F.SilkS")
			(hide yes)
			(effects
				(font
					(size 1.27 1.27)
				)
			)
		)
		(property "Value" "220R3F-1-GP"
			(at -0.0254 -2.5146 270)
			(unlocked yes)
			(layer "F.Fab")
			(hide yes)
			(effects
				(font
					(size 1.016 1.016)
					(thickness 0.1524)
				)
			)
		)
		(property "Device Type" "R603H22"
			(at -0.0254 -4.0386 270)
			(unlocked yes)
			(layer "F.Fab")
			(hide yes)
			(effects
				(font
					(size 1.016 1.016)
					(thickness 0.1524)
				)
			)
		)
		(duplicate_pad_numbers_are_jumpers no)
		(fp_line
			(start -0.4826 0)
			(end -0.2032 0)
			(stroke
				(width 0.2032)
				(type default)
			)
			(layer "F.SilkS")
		)
		(fp_line
			(start 0.2032 0)
			(end 0.4826 0)
			(stroke
				(width 0.2032)
				(type default)
			)
			(layer "F.SilkS")
		)
		(fp_rect
			(start -0.5842 1.3335)
			(end 0.5842 -1.3335)
			(stroke
				(width 0)
				(type default)
			)
			(fill no)
			(layer "F.CrtYd")
		)
		(fp_rect
			(start -0.5842 1.3335)
			(end 0.5842 -1.3335)
			(stroke
				(width 0)
				(type default)
			)
			(fill no)
			(layer "F.Fab")
		)
		(pad "1" smd custom
			(at 0 -0.762 270)
			(size 0.2159 0.2159)
			(layers "F.Cu" "F.Mask" "F.Paste")
			(net "HDD_PRSNT_32")
			(options
				(clearance outline)
				(anchor circle)
			)
			(primitives
				(gr_poly
					(pts
						(arc
							(start -0.3302 -0.4318)
							(mid -0.402042 -0.402042)
							(end -0.4318 -0.3302)
						)
						(arc
							(start -0.4318 0.3302)
							(mid -0.402042 0.402042)
							(end -0.3302 0.4318)
						)
						(arc
							(start 0.3302 0.4318)
							(mid 0.402042 0.402042)
							(end 0.4318 0.3302)
						)
						(arc
							(start 0.4318 -0.3302)
							(mid 0.402042 -0.402042)
							(end 0.3302 -0.4318)
						)
					)
					(width 0)
					(fill yes)
				)
			)
		)
		(pad "2" smd custom
			(at 0 0.762 270)
			(size 0.2159 0.2159)
			(layers "F.Cu" "F.Mask" "F.Paste")
			(net "DRIVE_A_32_INS")
			(options
				(clearance outline)
				(anchor circle)
			)
			(primitives
				(gr_poly
					(pts
						(arc
							(start -0.3302 -0.4318)
							(mid -0.402042 -0.402042)
							(end -0.4318 -0.3302)
						)
						(arc
							(start -0.4318 0.3302)
							(mid -0.402042 0.402042)
							(end -0.3302 0.4318)
						)
						(arc
							(start 0.3302 0.4318)
							(mid 0.402042 0.402042)
							(end 0.4318 0.3302)
						)
						(arc
							(start 0.4318 -0.3302)
							(mid 0.402042 -0.402042)
							(end 0.3302 -0.4318)
						)
					)
					(width 0)
					(fill yes)
				)
			)
		)
	)
	(footprint ""
		(layer "F.Cu")
		(at 54.546246 -278.554942 90)
		(property "Reference" "R164"
			(at 0 0 90)
			(layer "F.SilkS")
			(hide yes)
			(effects
				(font
					(size 1.27 1.27)
				)
			)
		)
		(property "Value" "4K7R2J-2-GP"
			(at 0.064008 -3.993896 90)
			(unlocked yes)
			(layer "F.Fab")
			(hide yes)
			(effects
				(font
					(size 1.016 1.016)
					(thickness 0.1524)
				)
			)
		)
		(property "Device Type" "R402H16"
			(at 0.064008 -5.517896 90)
			(unlocked yes)
			(layer "F.Fab")
			(hide yes)
			(effects
				(font
					(size 1.016 1.016)
					(thickness 0.1524)
				)
			)
		)
		(duplicate_pad_numbers_are_jumpers no)
		(fp_line
			(start 0.508 -0.9398)
			(end -0.508 -0.9398)
			(stroke
				(width 0.1524)
				(type default)
			)
			(layer "F.SilkS")
		)
		(fp_line
			(start -0.508 -0.9398)
			(end -0.508 0.9398)
			(stroke
				(width 0.1524)
				(type default)
			)
			(layer "F.SilkS")
		)
		(fp_rect
			(start -0.508 0.9398)
			(end 0.508 -0.9398)
			(stroke
				(width 0)
				(type default)
			)
			(fill no)
			(layer "F.CrtYd")
		)
		(fp_rect
			(start -0.508 0.9398)
			(end 0.508 -0.9398)
			(stroke
				(width 0)
				(type default)
			)
			(fill no)
			(layer "F.Fab")
		)
		(pad "1" smd custom
			(at 0 -0.4445 90)
			(size 0.1397 0.1397)
			(layers "F.Cu" "F.Mask" "F.Paste")
			(net "SW_PWR_R_HDD1")
			(options
				(clearance outline)
				(anchor circle)
			)
			(primitives
				(gr_poly
					(pts
						(arc
							(start -0.1778 -0.2794)
							(mid -0.249642 -0.249642)
							(end -0.2794 -0.1778)
						)
						(arc
							(start -0.2794 0.1778)
							(mid -0.249642 0.249642)
							(end -0.1778 0.2794)
						)
						(arc
							(start 0.1778 0.2794)
							(mid 0.249642 0.249642)
							(end 0.2794 0.1778)
						)
						(arc
							(start 0.2794 -0.1778)
							(mid 0.249642 -0.249642)
							(end 0.1778 -0.2794)
						)
					)
					(width 0)
					(fill yes)
				)
			)
		)
		(pad "2" smd custom
			(at 0 0.4445 90)
			(size 0.1397 0.1397)
			(layers "F.Cu" "F.Mask" "F.Paste")
			(net "GND")
			(options
				(clearance outline)
				(anchor circle)
			)
			(primitives
				(gr_poly
					(pts
						(arc
							(start -0.1778 -0.2794)
							(mid -0.249642 -0.249642)
							(end -0.2794 -0.1778)
						)
						(arc
							(start -0.2794 0.1778)
							(mid -0.249642 0.249642)
							(end -0.1778 0.2794)
						)
						(arc
							(start 0.1778 0.2794)
							(mid 0.249642 0.249642)
							(end 0.2794 0.1778)
						)
						(arc
							(start 0.2794 -0.1778)
							(mid 0.249642 -0.249642)
							(end 0.1778 -0.2794)
						)
					)
					(width 0)
					(fill yes)
				)
			)
		)
	)
	(footprint ""
		(layer "F.Cu")
		(at 140.992098 -45.608494 90)
		(property "Reference" "R788"
			(at 0 0 90)
			(layer "F.SilkS")
			(hide yes)
			(effects
				(font
					(size 1.27 1.27)
				)
			)
		)
		(property "Value" "4K7R2J-2-GP"
			(at 0.064008 -3.993896 90)
			(unlocked yes)
			(layer "F.Fab")
			(hide yes)
			(effects
				(font
					(size 1.016 1.016)
					(thickness 0.1524)
				)
			)
		)
		(property "Device Type" "R402H16"
			(at 0.064008 -5.517896 90)
			(unlocked yes)
			(layer "F.Fab")
			(hide yes)
			(effects
				(font
					(size 1.016 1.016)
					(thickness 0.1524)
				)
			)
		)
		(duplicate_pad_numbers_are_jumpers no)
		(fp_line
			(start 0.508 -0.9398)
			(end -0.508 -0.9398)
			(stroke
				(width 0.1524)
				(type default)
			)
			(layer "F.SilkS")
		)
		(fp_line
			(start -0.508 -0.9398)
			(end -0.508 0.9398)
			(stroke
				(width 0.1524)
				(type default)
			)
			(layer "F.SilkS")
		)
		(fp_rect
			(start -0.508 0.9398)
			(end 0.508 -0.9398)
			(stroke
				(width 0)
				(type default)
			)
			(fill no)
			(layer "F.CrtYd")
		)
		(fp_rect
			(start -0.508 0.9398)
			(end 0.508 -0.9398)
			(stroke
				(width 0)
				(type default)
			)
			(fill no)
			(layer "F.Fab")
		)
		(pad "1" smd custom
			(at 0 -0.4445 90)
			(size 0.1397 0.1397)
			(layers "F.Cu" "F.Mask" "F.Paste")
			(net "P12V_A")
			(options
				(clearance outline)
				(anchor circle)
			)
			(primitives
				(gr_poly
					(pts
						(arc
							(start -0.1778 -0.2794)
							(mid -0.249642 -0.249642)
							(end -0.2794 -0.1778)
						)
						(arc
							(start -0.2794 0.1778)
							(mid -0.249642 0.249642)
							(end -0.1778 0.2794)
						)
						(arc
							(start 0.1778 0.2794)
							(mid 0.249642 0.249642)
							(end 0.2794 0.1778)
						)
						(arc
							(start 0.2794 -0.1778)
							(mid 0.249642 -0.249642)
							(end 0.1778 -0.2794)
						)
					)
					(width 0)
					(fill yes)
				)
			)
		)
		(pad "2" smd custom
			(at 0 0.4445 90)
			(size 0.1397 0.1397)
			(layers "F.Cu" "F.Mask" "F.Paste")
			(net "SW_HDD_R28")
			(options
				(clearance outline)
				(anchor circle)
			)
			(primitives
				(gr_poly
					(pts
						(arc
							(start -0.1778 -0.2794)
							(mid -0.249642 -0.249642)
							(end -0.2794 -0.1778)
						)
						(arc
							(start -0.2794 0.1778)
							(mid -0.249642 0.249642)
							(end -0.1778 0.2794)
						)
						(arc
							(start 0.1778 0.2794)
							(mid 0.249642 0.249642)
							(end 0.2794 0.1778)
						)
						(arc
							(start 0.2794 -0.1778)
							(mid 0.249642 -0.249642)
							(end 0.1778 -0.2794)
						)
					)
					(width 0)
					(fill yes)
				)
			)
		)
	)
	(footprint ""
		(layer "F.Cu")
		(at 452.642224 -249.875548 90)
		(property "Reference" "C638"
			(at 0 0 90)
			(layer "F.SilkS")
			(hide yes)
			(effects
				(font
					(size 1.27 1.27)
				)
			)
		)
		(property "Value" "SCD1U16V2KX-3GP"
			(at 1.1811 -2.7051 90)
			(unlocked yes)
			(layer "F.Fab")
			(hide yes)
			(effects
				(font
					(size 1.016 1.016)
					(thickness 0.1524)
				)
			)
		)
		(property "Device Type" "C402H22"
			(at 1.1811 -4.2291 90)
			(unlocked yes)
			(layer "F.Fab")
			(hide yes)
			(effects
				(font
					(size 1.016 1.016)
					(thickness 0.1524)
				)
			)
		)
		(duplicate_pad_numbers_are_jumpers no)
		(fp_rect
			(start -0.4318 0.9525)
			(end 0.4318 -0.9525)
			(stroke
				(width 0)
				(type default)
			)
			(fill no)
			(layer "F.CrtYd")
		)
		(fp_rect
			(start -0.4318 0.9525)
			(end 0.4318 -0.9525)
			(stroke
				(width 0)
				(type default)
			)
			(fill no)
			(layer "F.Fab")
		)
		(pad "1" smd custom
			(at 0 -0.4445 90)
			(size 0.1524 0.1524)
			(layers "F.Cu" "F.Mask" "F.Paste")
			(net "P5V_C_VBST_RC")
			(options
				(clearance outline)
				(anchor circle)
			)
			(primitives
				(gr_poly
					(pts
						(arc
							(start 0.3048 -0.2032)
							(mid 0.275042 -0.275042)
							(end 0.2032 -0.3048)
						)
						(arc
							(start -0.2032 -0.3048)
							(mid -0.275042 -0.275042)
							(end -0.3048 -0.2032)
						)
						(arc
							(start -0.3048 0.2032)
							(mid -0.275042 0.275042)
							(end -0.2032 0.3048)
						)
						(arc
							(start 0.2032 0.3048)
							(mid 0.275042 0.275042)
							(end 0.3048 0.2032)
						)
					)
					(width 0)
					(fill yes)
				)
			)
		)
		(pad "2" smd custom
			(at 0 0.4445 90)
			(size 0.1524 0.1524)
			(layers "F.Cu" "F.Mask" "F.Paste")
			(net "P5V_C_LL")
			(options
				(clearance outline)
				(anchor circle)
			)
			(primitives
				(gr_poly
					(pts
						(arc
							(start 0.3048 -0.2032)
							(mid 0.275042 -0.275042)
							(end 0.2032 -0.3048)
						)
						(arc
							(start -0.2032 -0.3048)
							(mid -0.275042 -0.275042)
							(end -0.3048 -0.2032)
						)
						(arc
							(start -0.3048 0.2032)
							(mid -0.275042 0.275042)
							(end -0.2032 0.3048)
						)
						(arc
							(start 0.2032 0.3048)
							(mid 0.275042 0.275042)
							(end 0.3048 0.2032)
						)
					)
					(width 0)
					(fill yes)
				)
			)
		)
	)
	(footprint ""
		(layer "F.Cu")
		(at 161.997898 -291.127942 90)
		(property "Reference" "C98"
			(at 0 0 90)
			(layer "F.SilkS")
			(hide yes)
			(effects
				(font
					(size 1.27 1.27)
				)
			)
		)
		(property "Value" "SCD01U50V2KX-1GP"
			(at 1.1811 -2.7051 90)
			(unlocked yes)
			(layer "F.Fab")
			(hide yes)
			(effects
				(font
					(size 1.016 1.016)
					(thickness 0.1524)
				)
			)
		)
		(property "Device Type" "C402H22"
			(at 1.1811 -4.2291 90)
			(unlocked yes)
			(layer "F.Fab")
			(hide yes)
			(effects
				(font
					(size 1.016 1.016)
					(thickness 0.1524)
				)
			)
		)
		(duplicate_pad_numbers_are_jumpers no)
		(fp_rect
			(start -0.4318 0.9525)
			(end 0.4318 -0.9525)
			(stroke
				(width 0)
				(type default)
			)
			(fill no)
			(layer "F.CrtYd")
		)
		(fp_rect
			(start -0.4318 0.9525)
			(end 0.4318 -0.9525)
			(stroke
				(width 0)
				(type default)
			)
			(fill no)
			(layer "F.Fab")
		)
		(pad "1" smd custom
			(at 0 -0.4445 90)
			(size 0.1524 0.1524)
			(layers "F.Cu" "F.Mask" "F.Paste")
			(net "HDD_PRSNT_4")
			(options
				(clearance outline)
				(anchor circle)
			)
			(primitives
				(gr_poly
					(pts
						(arc
							(start 0.3048 -0.2032)
							(mid 0.275042 -0.275042)
							(end 0.2032 -0.3048)
						)
						(arc
							(start -0.2032 -0.3048)
							(mid -0.275042 -0.275042)
							(end -0.3048 -0.2032)
						)
						(arc
							(start -0.3048 0.2032)
							(mid -0.275042 0.275042)
							(end -0.2032 0.3048)
						)
						(arc
							(start 0.2032 0.3048)
							(mid 0.275042 0.275042)
							(end 0.3048 0.2032)
						)
					)
					(width 0)
					(fill yes)
				)
			)
		)
		(pad "2" smd custom
			(at 0 0.4445 90)
			(size 0.1524 0.1524)
			(layers "F.Cu" "F.Mask" "F.Paste")
			(net "GND")
			(options
				(clearance outline)
				(anchor circle)
			)
			(primitives
				(gr_poly
					(pts
						(arc
							(start 0.3048 -0.2032)
							(mid 0.275042 -0.275042)
							(end 0.2032 -0.3048)
						)
						(arc
							(start -0.2032 -0.3048)
							(mid -0.275042 -0.275042)
							(end -0.3048 -0.2032)
						)
						(arc
							(start -0.3048 0.2032)
							(mid -0.275042 0.275042)
							(end -0.2032 0.3048)
						)
						(arc
							(start 0.2032 0.3048)
							(mid 0.275042 0.275042)
							(end 0.3048 0.2032)
						)
					)
					(width 0)
					(fill yes)
				)
			)
		)
	)
)
